FILE_TYPE = CONNECTIVITY;
{Allegro Design Entry HDL 17.2-2016 S081 (4005846) 1/11/2022}
"PAGE_NUMBER" = 27;
0"NC";
1"P3V3_AUX\g";
2"P3V3_AUX\g";
3"P3V3_AUX\g";
4"P3V3_AUX\g";
5"P3V3_AUX\g";
6"P3V3_RGM\g";
7"P3V3_AUX\g";
8"P3V3_AUX\g";
9"P3V3_AUX\g";
10"GND\g";
11"GND\g";
12"GND\g";
13"GND\g";
14"SMB_BMC_MM4_SCL";
15"SMB_BMC_MM2_SDA";
16"SMB_BMC_MM2_SCL";
17"SMB_BMC_MM1_SCL";
18"SMB_BMC_MM1_SDA";
19"SMB_BMC_MM3_SCL";
20"SMB_BMC_MM3_SDA";
21"SMB_BMC_MM4_SDA";
22"SMB_BMC_MM5_R_SCL";
23"SMB_BMC_MM5_R_SDA";
24"SMB_BMC_MM6_SCL";
25"SMB_BMC_MM6_SDA";
26"SMB_BMC_MM7_R_SCL";
27"SMB_BMC_MM7_R_SDA";
28"SMB_BMC_MM9_SCL";
29"SMB_BMC_MM12_SCL";
30"SMB_BMC_MM12_SDA";
31"SMB_BMC_MM16_SDA";
32"SMB_BMC_MM8_SCL";
33"SMB_BMC_MM10_SDA";
34"SMB_BMC_ALERT10_N";
35"FM_ME_BT_DONE";
36"SMB_BMC_MM15_SCL";
37"SMB_BMC_MM15_SDA";
38"SMB_BMC_MM16_SCL";
39"SMB_BMC_ALERT9_N";
40"SMB_BMC_ALERT4_N";
41"SMB_BMC_ALERT3_N";
42"VOL_SEN_ALERT_R";
43"SMB_BMC_ALERT12_N";
44"SMB_BMC_MM9_SDA";
45"FM_BMC_EN_DET_R";
46"SPI_BMC_BOOT_MOSI";
47"SPI_BMC_BOOT_MISO";
48"SMB_BMC_MM10_SCL";
49"SMB_BMC_MM8_SDA";
50"SPI_BMC_TPM_MOSI";
51"UART_BMC_5_TXD_R";
52"SMB_BMC_MM14_SDA";
53"SMB_BMC_MM14_SCL";
54"FM_BMC_ONCTL_R_N";
55"UART_BMC_5_TXD_R";
56"SMB_BMC_MM13_SDA";
57"SMB_BMC_MM13_SCL";
58"SMB_BMC_ALERT15_N";
59"SMB_BMC_ALERT16_N";
60"Q7_D";
61"LPC_ESPI_SEL_R1";
62"LPC_ESPI_SEL";
63"SPI_BMC_BOOT_CLK";
64"FM_BMC_DISABLE";
%"Q_RES"
"1","(-3625,2975)","0","pure_quanta","I100";
;
MATERIAL"CHIP"
VALUE"2.2K"
TOLERANCE"5%"
PART_NUMBER"CS22202JB07"
PACK_TYPE"0402LF"
WATTAGE"1/16W"
CDS_LIB"pure_quanta"
LOCATION"R256"
$SEC"1"
CDS_SEC"1";
"B"
$PN"2"26;
"A"
$PN"1"1;
%"Q_RES"
"1","(-3625,3175)","0","pure_quanta","I101";
;
MATERIAL"CHIP"
VALUE"10K"
PART_NUMBER"CS31002FB08"
TOLERANCE"1%"
CDS_LIB"pure_quanta"
WATTAGE"1/16W"
PACK_TYPE"0402LF"
LOCATION"R254"
$SEC"1"
CDS_SEC"1";
"B"
$PN"2"24;
"A"
$PN"1"1;
%"Q_RES"
"1","(-3625,3075)","0","pure_quanta","I102";
;
VALUE"10K"
MATERIAL"CHIP"
PART_NUMBER"CS31002FB08"
TOLERANCE"1%"
CDS_LIB"pure_quanta"
WATTAGE"1/16W"
PACK_TYPE"0402LF"
LOCATION"R255"
$SEC"1"
CDS_SEC"1";
"B"
$PN"2"25;
"A"
$PN"1"1;
%"Q_RES"
"1","(-3625,3275)","0","pure_quanta","I103";
;
MATERIAL"CHIP"
VALUE"2.2K"
TOLERANCE"5%"
PART_NUMBER"CS22202JB07"
PACK_TYPE"0402LF"
WATTAGE"1/16W"
CDS_LIB"pure_quanta"
LOCATION"R253"
$SEC"1"
CDS_SEC"1";
"B"
$PN"2"23;
"A"
$PN"1"1;
%"Q_RES"
"1","(-3625,3375)","0","pure_quanta","I105";
;
MATERIAL"CHIP"
VALUE"2.2K"
TOLERANCE"5%"
PART_NUMBER"CS22202JB07"
PACK_TYPE"0402LF"
WATTAGE"1/16W"
CDS_LIB"pure_quanta"
LOCATION"R252"
$SEC"1"
CDS_SEC"1";
"B"
$PN"2"22;
"A"
$PN"1"1;
%"Q_RES"
"1","(-3625,3575)","0","pure_quanta","I106";
;
MATERIAL"CHIP"
VALUE"402"
WATTAGE"1/16W"
PACK_TYPE"0402LF"
TOLERANCE"1%"
CDS_LIB"pure_quanta"
PART_NUMBER"CS14022FB02"
LOCATION"R250"
$SEC"1"
CDS_SEC"1";
"B"
$PN"2"14;
"A"
$PN"1"1;
%"Q_RES"
"1","(-3625,3775)","0","pure_quanta","I107";
;
VALUE"2.2K"
MATERIAL"CHIP"
TOLERANCE"5%"
PART_NUMBER"CS22202JB07"
PACK_TYPE"0402LF"
WATTAGE"1/16W"
CDS_LIB"pure_quanta"
LOCATION"R248"
$SEC"1"
CDS_SEC"1";
"B"
$PN"2"19;
"A"
$PN"1"1;
%"Q_RES"
"1","(-3625,3675)","0","pure_quanta","I108";
;
VALUE"2.2K"
MATERIAL"CHIP"
TOLERANCE"5%"
PART_NUMBER"CS22202JB07"
PACK_TYPE"0402LF"
WATTAGE"1/16W"
CDS_LIB"pure_quanta"
LOCATION"R249"
$SEC"1"
CDS_SEC"1";
"B"
$PN"2"20;
"A"
$PN"1"1;
%"Q_RES"
"1","(-3625,3875)","0","pure_quanta","I109";
;
VALUE"2.2K"
MATERIAL"CHIP"
TOLERANCE"5%"
PART_NUMBER"CS22202JB07"
PACK_TYPE"0402LF"
WATTAGE"1/16W"
CDS_LIB"pure_quanta"
LOCATION"R247"
$SEC"1"
CDS_SEC"1";
"B"
$PN"2"15;
"A"
$PN"1"1;
%"UNIVERSAL_POWER"
"1","(-4075,4325)","0","logical_power","I110";
;
HDL_POWER"P3V3_AUX"
CDS_LIB"logical_power";
"A"1;
%"Q_RES"
"1","(-3625,3975)","0","pure_quanta","I145";
;
VALUE"2.2K"
MATERIAL"CHIP"
TOLERANCE"5%"
PART_NUMBER"CS22202JB07"
PACK_TYPE"0402LF"
WATTAGE"1/16W"
CDS_LIB"pure_quanta"
LOCATION"R246"
$SEC"1"
CDS_SEC"1";
"B"
$PN"2"16;
"A"
$PN"1"1;
%"Q_RES"
"1","(-3625,4075)","0","pure_quanta","I146";
;
VALUE"1.8K"
MATERIAL"CHIP"
CDS_LIB"pure_quanta"
WATTAGE"1/16W"
PACK_TYPE"0402LF"
TOLERANCE"1%"
PART_NUMBER"CS21802FB10"
LOCATION"R245"
$SEC"1"
CDS_SEC"1";
"B"
$PN"2"18;
"A"
$PN"1"1;
%"Q_RES"
"1","(-3625,4175)","0","pure_quanta","I147";
;
MATERIAL"CHIP"
VALUE"1.8K"
CDS_LIB"pure_quanta"
WATTAGE"1/16W"
PACK_TYPE"0402LF"
TOLERANCE"1%"
PART_NUMBER"CS21802FB10"
LOCATION"R244"
$SEC"1"
CDS_SEC"1";
"B"
$PN"2"17;
"A"
$PN"1"1;
%"VCCAUX15"
"1","(2375,-100)","0","logical_power","I160";
;
HDL_POWER"P3V3_AUX"
CDS_LIB"logical_power";
"A"5;
%"Q_RES"
"1","(2500,500)","0","pure_quanta","I163";
;
MATERIAL"EMPTY"
VALUE"4.7K"
PART_NUMBER"CS24702FB06"
PACK_TYPE"0402LF"
WATTAGE"1/16W"
TOLERANCE"1%"
CDS_LIB"pure_quanta"
LOCATION"R699"
$SEC"1"
CDS_SEC"1";
"B"
$PN"2"63;
"A"
$PN"1"7;
%"VCCAUX15"
"1","(2100,750)","0","logical_power","I164";
;
HDL_POWER"P3V3_AUX"
CDS_LIB"logical_power";
"A"7;
%"Q_RES"
"1","(2225,-675)","0","pure_quanta","I165";
;
MATERIAL"CHIP"
TOLERANCE"1%"
VALUE"2K"
WATTAGE"1/16W"
PACK_TYPE"0402LF"
PART_NUMBER"CS22002FB07"
CDS_LIB"pure_quanta"
LOCATION"R714"
$SEC"1"
CDS_SEC"1";
"B"
$PN"2"61;
"A"
$PN"1"62;
%"Q_CAP"
"1","(2650,-900)","0","pure_quanta","I166";
;
TOLERANCE"10%"
PACK_TYPE"0402"
VOLTAGE"16V"
VALUE"1UF"
PART_NUMBER"TMP_QCH5103K9B00"
MATERIAL"EMPTY"
CDS_LIB"pure_quanta"
LOCATION"C267"
$SEC"1"
CDS_SEC"1";
"B"
$PN"2"12;
"A"
$PN"1"61;
%"UNIVERSAL_GND"
"1","(2650,-1125)","0","logical_power","I167";
;
HDL_POWER"GND"
CDS_LIB"logical_power";
"A"12;
%"Q_RES"
"1","(-3625,1050)","0","pure_quanta","I168";
;
VALUE"4.7K"
MATERIAL"CHIP"
PART_NUMBER"CS24702FB06"
PACK_TYPE"0402LF"
WATTAGE"1/16W"
TOLERANCE"1%"
CDS_LIB"pure_quanta"
LOCATION"R842"
$SEC"1"
CDS_SEC"1";
"B"
$PN"2"39;
"A"
$PN"1"2;
%"Q_RES"
"1","(-3625,975)","0","pure_quanta","I177";
;
VALUE"4.7K"
MATERIAL"CHIP"
PART_NUMBER"CS24702FB06"
PACK_TYPE"0402LF"
WATTAGE"1/16W"
TOLERANCE"1%"
CDS_LIB"pure_quanta"
LOCATION"R843"
$SEC"1"
CDS_SEC"1";
"B"
$PN"2"34;
"A"
$PN"1"2;
%"Q_RES"
"1","(-3625,825)","0","pure_quanta","I179";
;
VALUE"4.7K"
MATERIAL"CHIP"
PART_NUMBER"CS24702FB06"
PACK_TYPE"0402LF"
WATTAGE"1/16W"
TOLERANCE"1%"
CDS_LIB"pure_quanta"
LOCATION"R844"
$SEC"1"
CDS_SEC"1";
"B"
$PN"2"43;
"A"
$PN"1"2;
%"Q_RES"
"1","(-3625,675)","0","pure_quanta","I181";
;
VALUE"4.7K"
MATERIAL"EMPTY"
PART_NUMBER"CS24702FB06"
PACK_TYPE"0402LF"
WATTAGE"1/16W"
TOLERANCE"1%"
CDS_LIB"pure_quanta"
LOCATION"R846"
$SEC"1"
CDS_SEC"1";
"B"
$PN"2"45;
"A"
$PN"1"2;
%"Q_RES"
"1","(-3625,525)","0","pure_quanta","I182";
;
VALUE"4.7K"
MATERIAL"CHIP"
PART_NUMBER"CS24702FB06"
PACK_TYPE"0402LF"
WATTAGE"1/16W"
TOLERANCE"1%"
CDS_LIB"pure_quanta"
LOCATION"R848"
$SEC"1"
CDS_SEC"1";
"B"
$PN"2"59;
"A"
$PN"1"2;
%"Q_RES"
"1","(-3625,600)","0","pure_quanta","I184";
;
VALUE"4.7K"
MATERIAL"CHIP"
PART_NUMBER"CS24702FB06"
PACK_TYPE"0402LF"
WATTAGE"1/16W"
TOLERANCE"1%"
CDS_LIB"pure_quanta"
LOCATION"R851"
$SEC"1"
CDS_SEC"1";
"B"
$PN"2"58;
"A"
$PN"1"2;
%"BAT54C"
"1","(2800,2150)","6","pure_quanta","I185";
;
PART_NUMBER"BCBAT54CZ04"
MATERIAL"IC"
PART_TYPE"SMLF"
VALUE"BAT54C"
NEEDS_NO_SIZE"TRUE"
CDS_LIB"pure_quanta"
LOCATION"U11"
$SEC"1"
CDS_SEC"1";
"C"
$PN"3"64;
"A"
$PN"2"55;
"B"
$PN"1"54;
%"Q_RES"
"2","(2750,2625)","0","pure_quanta","I188";
;
PACK_TYPE"0402LF"
MATERIAL"CHIP"
WATTAGE"1/16W"
TOLERANCE"1%"
VALUE"4.7K"
PART_NUMBER"CS24702FB06"
CDS_LIB"pure_quanta"
LOCATION"R430"
$SEC"1"
CDS_SEC"1";
"A"
$PN"1"9;
"B"
$PN"2"54;
%"UNIVERSAL_POWER"
"1","(2750,2875)","0","logical_power","I189";
;
HDL_POWER"P3V3_AUX"
CDS_LIB"logical_power";
"A"9;
%"UNIVERSAL_POWER"
"1","(-1075,4350)","0","logical_power","I204";
;
HDL_POWER"P3V3_AUX"
CDS_LIB"logical_power";
"A"8;
%"Q_RES"
"1","(-675,2725)","0","pure_quanta","I213";
;
VALUE"4.7K"
MATERIAL"EMPTY"
PART_NUMBER"CS24702FB06"
PACK_TYPE"0402LF"
WATTAGE"1/16W"
TOLERANCE"1%"
CDS_LIB"pure_quanta"
LOCATION"R754"
$SEC"1"
CDS_SEC"1";
"B"
$PN"2"51;
"A"
$PN"1"6;
%"UNIVERSAL_POWER"
"1","(-1075,2975)","0","logical_power","I214";
;
HDL_POWER"P3V3_RGM"
CDS_LIB"logical_power";
"A"6;
%"Q_RES"
"1","(-675,2525)","0","pure_quanta","I217";
;
VALUE"4.7K"
MATERIAL"EMPTY"
PART_NUMBER"CS24702FB06"
PACK_TYPE"0402LF"
WATTAGE"1/16W"
TOLERANCE"1%"
CDS_LIB"pure_quanta"
LOCATION"R770"
$SEC"1"
CDS_SEC"1";
"B"
$PN"2"51;
"A"
$PN"1"13;
%"UNIVERSAL_GND"
"1","(-1075,2325)","2","logical_power","I218";
;
HDL_POWER"GND"
CDS_LIB"logical_power";
"A"13;
%"Q_RES"
"2","(2375,-275)","0","pure_quanta","I222";
;
VALUE"4.7K"
TOLERANCE"1%"
PACK_TYPE"0402LF"
PART_NUMBER"CS24702FB06"
MATERIAL"CHIP"
CDS_LIB"pure_quanta"
WATTAGE"1/16W"
LOCATION"R42"
$SEC"1"
CDS_SEC"1";
"A"
$PN"1"5;
"B"
$PN"2"60;
%"UNIVERSAL_GND"
"1","(-3325,-1300)","2","logical_power","I223";
;
CDS_LIB"logical_power"
HDL_POWER"GND";
"A"11;
%"Q_RES"
"2","(-3325,-150)","0","pure_quanta","I228";
;
VALUE"4.7K"
TOLERANCE"1%"
PACK_TYPE"0402LF"
MATERIAL"EMPTY"
WATTAGE"1/16W"
CDS_LIB"pure_quanta"
PART_NUMBER"CS24702FB06"
LOCATION"R140"
$SEC"1"
CDS_SEC"1";
"A"
$PN"1"3;
"B"
$PN"2"46;
%"VCCAUX15"
"1","(-3325,175)","0","logical_power","I231";
;
HDL_POWER"P3V3_AUX"
CDS_LIB"logical_power";
"A"3;
%"VCCAUX15"
"1","(-2825,175)","0","logical_power","I232";
;
HDL_POWER"P3V3_AUX"
CDS_LIB"logical_power";
"A"4;
%"Q_RES"
"2","(-2825,-150)","0","pure_quanta","I233";
;
WATTAGE"1/16W"
VALUE"4.7K"
TOLERANCE"1%"
PACK_TYPE"0402LF"
MATERIAL"EMPTY"
PART_NUMBER"CS24702FB06"
CDS_LIB"pure_quanta"
LOCATION"R753"
$SEC"1"
CDS_SEC"1";
"A"
$PN"1"4;
"B"
$PN"2"47;
%"Q_RES"
"1","(-3625,2275)","0","pure_quanta","I234";
;
VALUE"10K"
MATERIAL"CHIP"
PART_NUMBER"CS31002FB08"
TOLERANCE"1%"
CDS_LIB"pure_quanta"
PACK_TYPE"0402LF"
WATTAGE"1/16W"
LOCATION"R521"
$SEC"1"
CDS_SEC"1";
"B"
$PN"2"33;
"A"
$PN"1"1;
%"Q_RES"
"1","(-3625,2175)","0","pure_quanta","I235";
;
MATERIAL"CHIP"
VALUE"10K"
PART_NUMBER"CS31002FB08"
TOLERANCE"1%"
CDS_LIB"pure_quanta"
WATTAGE"1/16W"
PACK_TYPE"0402LF"
LOCATION"R145"
$SEC"1"
CDS_SEC"1";
"B"
$PN"2"29;
"A"
$PN"1"1;
%"Q_RES"
"1","(-3625,2075)","0","pure_quanta","I236";
;
VALUE"10K"
MATERIAL"CHIP"
PART_NUMBER"CS31002FB08"
TOLERANCE"1%"
CDS_LIB"pure_quanta"
WATTAGE"1/16W"
PACK_TYPE"0402LF"
LOCATION"R149"
$SEC"1"
CDS_SEC"1";
"B"
$PN"2"30;
"A"
$PN"1"1;
%"Q_RES"
"1","(-3625,1975)","0","pure_quanta","I237";
;
VALUE"2.2K"
MATERIAL"CHIP"
PACK_TYPE"0402LF"
WATTAGE"1/16W"
PART_NUMBER"CS22202JB07"
TOLERANCE"5%"
CDS_LIB"pure_quanta"
LOCATION"R610"
$SEC"1"
CDS_SEC"1";
"B"
$PN"2"36;
"A"
$PN"1"1;
%"Q_RES"
"1","(-3625,1875)","0","pure_quanta","I238";
;
VALUE"2.2K"
MATERIAL"CHIP"
PACK_TYPE"0402LF"
WATTAGE"1/16W"
PART_NUMBER"CS22202JB07"
TOLERANCE"5%"
CDS_LIB"pure_quanta"
LOCATION"R692"
$SEC"1"
CDS_SEC"1";
"B"
$PN"2"37;
"A"
$PN"1"1;
%"Q_RES"
"1","(-625,4200)","0","pure_quanta","I239";
;
MATERIAL"CHIP"
VALUE"2.2K"
PACK_TYPE"0402LF"
WATTAGE"1/16W"
PART_NUMBER"CS22202JB07"
TOLERANCE"5%"
CDS_LIB"pure_quanta"
LOCATION"R422"
$SEC"1"
CDS_SEC"1";
"B"
$PN"2"57;
"A"
$PN"1"8;
%"Q_RES"
"1","(-625,4100)","0","pure_quanta","I240";
;
MATERIAL"CHIP"
VALUE"2.2K"
PACK_TYPE"0402LF"
WATTAGE"1/16W"
PART_NUMBER"CS22202JB07"
TOLERANCE"5%"
CDS_LIB"pure_quanta"
LOCATION"R428"
$SEC"1"
CDS_SEC"1";
"B"
$PN"2"56;
"A"
$PN"1"8;
%"Q_RES"
"1","(-625,4000)","0","pure_quanta","I241";
;
MATERIAL"CHIP"
VALUE"2.2K"
PACK_TYPE"0402LF"
WATTAGE"1/16W"
PART_NUMBER"CS22202JB07"
TOLERANCE"5%"
CDS_LIB"pure_quanta"
LOCATION"R429"
$SEC"1"
CDS_SEC"1";
"B"
$PN"2"53;
"A"
$PN"1"8;
%"Q_RES"
"1","(-625,3900)","0","pure_quanta","I242";
;
MATERIAL"CHIP"
VALUE"2.2K"
PACK_TYPE"0402LF"
WATTAGE"1/16W"
PART_NUMBER"CS22202JB07"
TOLERANCE"5%"
CDS_LIB"pure_quanta"
LOCATION"R438"
$SEC"1"
CDS_SEC"1";
"B"
$PN"2"52;
"A"
$PN"1"8;
%"2N7002A7"
"1","(3350,-700)","0","pure_quanta","I243";
;
MATERIAL"IC"
PART_TYPE"SMLF"
PART_NUMBER"BAM70020068"
VALUE"2N7002A-7"
CDS_LIB"pure_quanta"
NEEDS_NO_SIZE"TRUE"
CDS_LMAN_SYM_OUTLINE"-300,325,300,-325"
LOCATION"Q7"
$SEC"1"
CDS_SEC"1";
"S"
$PN"S"50;
"D"
$PN"D"60;
"G"
$PN"G"61;
%"Q_RES"
"2","(-2825,-1000)","0","pure_quanta","I244";
;
PACK_TYPE"0402LF"
PART_NUMBER"CS11002FB07"
TOLERANCE"1%"
VALUE"100"
WATTAGE"1/16W"
MATERIAL"EMPTY"
CDS_LIB"pure_quanta"
$LOCATION"R164"
CDS_LOCATION"R164"
$SEC"1"
CDS_SEC"1";
"A"
$PN"1"47;
"B"
$PN"2"10;
%"UNIVERSAL_GND"
"1","(-2825,-1300)","2","logical_power","I245";
;
CDS_LIB"logical_power"
HDL_POWER"GND";
"A"10;
%"Q_RES"
"2","(-3325,-975)","0","pure_quanta","I246";
;
WATTAGE"1/16W"
VALUE"4.7K"
TOLERANCE"1%"
PACK_TYPE"0402LF"
MATERIAL"CHIP"
PART_NUMBER"CS24702FB06"
CDS_LIB"pure_quanta"
LOCATION"R94"
$SEC"1"
CDS_SEC"1";
"A"
$PN"1"46;
"B"
$PN"2"11;
%"Q_RES"
"1","(-3625,3475)","0","pure_quanta","I247";
;
VALUE"499"
PART_NUMBER"CS14992FB06"
MATERIAL"CHIP"
CDS_LIB"pure_quanta"
WATTAGE"1/16W"
TOLERANCE"1%"
PACK_TYPE"0402LF"
LOCATION"R251"
$SEC"1"
CDS_SEC"1";
"B"
$PN"2"21;
"A"
$PN"1"1;
%"Q_RES"
"1","(-3625,1125)","0","pure_quanta","I84";
;
VALUE"4.7K"
MATERIAL"CHIP"
CDS_LIB"pure_quanta"
TOLERANCE"1%"
WATTAGE"1/16W"
PACK_TYPE"0402LF"
PART_NUMBER"CS24702FB06"
LOCATION"R269"
$SEC"1"
CDS_SEC"1";
"B"
$PN"2"40;
"A"
$PN"1"2;
%"Q_RES"
"1","(-3625,1275)","0","pure_quanta","I85";
;
VALUE"4.7K"
MATERIAL"EMPTY"
CDS_LIB"pure_quanta"
TOLERANCE"1%"
WATTAGE"1/16W"
PACK_TYPE"0402LF"
PART_NUMBER"CS24702FB06"
LOCATION"R267"
$SEC"1"
CDS_SEC"1";
"B"
$PN"2"42;
"A"
$PN"1"2;
%"Q_RES"
"1","(-3625,1200)","0","pure_quanta","I86";
;
MATERIAL"CHIP"
VALUE"4.7K"
CDS_LIB"pure_quanta"
TOLERANCE"1%"
WATTAGE"1/16W"
PACK_TYPE"0402LF"
PART_NUMBER"CS24702FB06"
LOCATION"R268"
$SEC"1"
CDS_SEC"1";
"B"
$PN"2"41;
"A"
$PN"1"2;
%"UNIVERSAL_POWER"
"1","(-4075,1500)","0","logical_power","I87";
;
HDL_POWER"P3V3_AUX"
CDS_LIB"logical_power";
"A"2;
%"Q_RES"
"1","(-3625,1675)","0","pure_quanta","I88";
;
VALUE"2.2K"
MATERIAL"CHIP"
TOLERANCE"5%"
PART_NUMBER"CS22202JB07"
PACK_TYPE"0402LF"
WATTAGE"1/16W"
CDS_LIB"pure_quanta"
LOCATION"R265"
$SEC"1"
CDS_SEC"1";
"B"
$PN"2"31;
"A"
$PN"1"1;
%"Q_RES"
"1","(-3625,1775)","0","pure_quanta","I89";
;
MATERIAL"CHIP"
VALUE"2.2K"
TOLERANCE"5%"
PART_NUMBER"CS22202JB07"
PACK_TYPE"0402LF"
WATTAGE"1/16W"
CDS_LIB"pure_quanta"
LOCATION"R264"
$SEC"1"
CDS_SEC"1";
"B"
$PN"2"38;
"A"
$PN"1"1;
%"Q_RES"
"1","(-3625,2375)","0","pure_quanta","I93";
;
VALUE"10K"
MATERIAL"CHIP"
PART_NUMBER"CS31002FB08"
TOLERANCE"1%"
WATTAGE"1/16W"
PACK_TYPE"0402LF"
CDS_LIB"pure_quanta"
LOCATION"R262"
$SEC"1"
CDS_SEC"1";
"B"
$PN"2"48;
"A"
$PN"1"1;
%"Q_RES"
"1","(-3625,2475)","0","pure_quanta","I94";
;
MATERIAL"CHIP"
VALUE"10K"
PART_NUMBER"CS31002FB08"
TOLERANCE"1%"
CDS_LIB"pure_quanta"
WATTAGE"1/16W"
PACK_TYPE"0402LF"
LOCATION"R261"
$SEC"1"
CDS_SEC"1";
"B"
$PN"2"44;
"A"
$PN"1"1;
%"Q_RES"
"1","(-3625,1350)","0","pure_quanta","I95";
;
VALUE"4.7K"
MATERIAL"EMPTY"
CDS_LIB"pure_quanta"
TOLERANCE"1%"
WATTAGE"1/16W"
PACK_TYPE"0402LF"
PART_NUMBER"CS24702FB06"
LOCATION"R266"
$SEC"1"
CDS_SEC"1";
"B"
$PN"2"35;
"A"
$PN"1"2;
%"Q_RES"
"1","(-3625,2675)","0","pure_quanta","I96";
;
MATERIAL"CHIP"
VALUE"2.2K"
TOLERANCE"5%"
PART_NUMBER"CS22202JB07"
PACK_TYPE"0402LF"
WATTAGE"1/16W"
CDS_LIB"pure_quanta"
LOCATION"R259"
$SEC"1"
CDS_SEC"1";
"B"
$PN"2"49;
"A"
$PN"1"1;
%"Q_RES"
"1","(-3625,2575)","0","pure_quanta","I97";
;
VALUE"10K"
MATERIAL"CHIP"
PART_NUMBER"CS31002FB08"
TOLERANCE"1%"
CDS_LIB"pure_quanta"
WATTAGE"1/16W"
PACK_TYPE"0402LF"
LOCATION"R260"
$SEC"1"
CDS_SEC"1";
"B"
$PN"2"28;
"A"
$PN"1"1;
%"Q_RES"
"1","(-3625,2775)","0","pure_quanta","I98";
;
MATERIAL"CHIP"
VALUE"2.2K"
TOLERANCE"5%"
PART_NUMBER"CS22202JB07"
PACK_TYPE"0402LF"
WATTAGE"1/16W"
CDS_LIB"pure_quanta"
LOCATION"R258"
$SEC"1"
CDS_SEC"1";
"B"
$PN"2"32;
"A"
$PN"1"1;
%"Q_RES"
"1","(-3625,2875)","0","pure_quanta","I99";
;
VALUE"2.2K"
MATERIAL"CHIP"
TOLERANCE"5%"
PART_NUMBER"CS22202JB07"
PACK_TYPE"0402LF"
WATTAGE"1/16W"
CDS_LIB"pure_quanta"
LOCATION"R257"
$SEC"1"
CDS_SEC"1";
"B"
$PN"2"27;
"A"
$PN"1"1;
END.
